(kicad_pcb
	(version 20260206)
	(generator "pcbnew")
	(generator_version "10.0")
	(general
		(thickness 1.6)
		(legacy_teardrops no)
	)
	(paper "A4")
	(title_block
		(title "pdpb — Lightning_PDPB_BRD.brd")
		(comment 1 "Lightning (Wiwynn / Facebook NVMe JBOF) / footprints 366-372 of 1140")
	)
	(layers
		(0 "F.Cu" signal "TOP")
		(4 "In1.Cu" signal "L2GND")
		(6 "In2.Cu" signal "L3")
		(8 "In3.Cu" signal "L4VCC")
		(10 "In4.Cu" signal "L5VCC")
		(12 "In5.Cu" signal "L6")
		(14 "In6.Cu" signal "L7GND")
		(2 "B.Cu" signal "BOTTOM")
		(9 "F.Adhes" user "F.Adhesive")
		(11 "B.Adhes" user "B.Adhesive")
		(13 "F.Paste" user "Package Geometry/Pastemask Top")
		(15 "B.Paste" user "Package Geometry/Pastemask Bottom")
		(5 "F.SilkS" user "Ref Des/Silkscreen Top")
		(7 "B.SilkS" user "Ref Des/Silkscreen Bottom")
		(1 "F.Mask" user "Board Geometry/Soldermask Top")
		(3 "B.Mask" user "Board Geometry/Soldermask Bottom")
		(17 "Dwgs.User" user "User.Drawings")
		(19 "Cmts.User" user "User.Comments")
		(21 "Eco1.User" user "User.Eco1")
		(23 "Eco2.User" user "User.Eco2")
		(25 "Edge.Cuts" user "Board Geometry/Outline")
		(27 "Margin" user)
		(31 "F.CrtYd" user "Package Geometry/Place Bound Top")
		(29 "B.CrtYd" user "Package Geometry/Place Bound Bottom")
		(35 "F.Fab" user "Ref Des/Assembly Top")
		(33 "B.Fab" user "Ref Des/Assembly Bottom")
	)
	(footprint ""
		(layer "F.Cu")
		(at 228.2698 -196.7484)
		(property "Reference" "R9261"
			(at 0 0 0)
			(layer "F.SilkS")
			(hide yes)
			(effects
				(font
					(size 1.27 1.27)
				)
			)
		)
		(property "Value" "2R2010F-GP"
			(at 0.0762 -4.5466 0)
			(unlocked yes)
			(layer "F.Fab")
			(hide yes)
			(effects
				(font
					(size 1.016 1.016)
					(thickness 0.1524)
				)
			)
		)
		(property "Device Type" "R2010H26"
			(at 0.0762 -6.1468 0)
			(unlocked yes)
			(layer "F.Fab")
			(hide yes)
			(effects
				(font
					(size 1.016 1.016)
					(thickness 0.1524)
				)
			)
		)
		(duplicate_pad_numbers_are_jumpers no)
		(fp_line
			(start -3.302 -1.651)
			(end -3.302 1.651)
			(stroke
				(width 0.1524)
				(type default)
			)
			(layer "F.SilkS")
		)
		(fp_line
			(start -3.302 1.651)
			(end 3.302 1.651)
			(stroke
				(width 0.1524)
				(type default)
			)
			(layer "F.SilkS")
		)
		(fp_line
			(start 3.302 -1.651)
			(end -3.302 -1.651)
			(stroke
				(width 0.1524)
				(type default)
			)
			(layer "F.SilkS")
		)
		(fp_line
			(start 3.302 1.651)
			(end 3.302 -1.651)
			(stroke
				(width 0.1524)
				(type default)
			)
			(layer "F.SilkS")
		)
		(fp_rect
			(start -3.3782 1.7272)
			(end 3.3782 -1.7272)
			(stroke
				(width 0)
				(type default)
			)
			(fill no)
			(layer "F.CrtYd")
		)
		(fp_poly
			(pts
				(xy 3.3782 -1.7272) (xy -3.3782 -1.7272) (xy -3.3782 1.7272) (xy 3.3782 1.7272)
			)
			(stroke
				(width 0)
				(type default)
			)
			(fill no)
			(layer "F.Fab")
		)
		(pad "1" smd rect
			(at -2.3495 0)
			(size 1.143 2.794)
			(layers "F.Cu" "F.Mask" "F.Paste")
			(net "P12V_SSD3")
		)
		(pad "2" smd rect
			(at 2.3495 0)
			(size 1.143 2.794)
			(layers "F.Cu" "F.Mask" "F.Paste")
			(net "12V_PRECH_SSD3")
		)
	)
	(footprint ""
		(layer "F.Cu")
		(at 99.314 -296.545)
		(property "Reference" "R9076"
			(at 0 0 0)
			(layer "F.SilkS")
			(hide yes)
			(effects
				(font
					(size 1.27 1.27)
				)
			)
		)
		(property "Value" "27R2F-GP"
			(at 0.064008 -3.993896 0)
			(unlocked yes)
			(layer "F.Fab")
			(hide yes)
			(effects
				(font
					(size 1.016 1.016)
					(thickness 0.1524)
				)
			)
		)
		(property "Device Type" "R402H16"
			(at 0.064008 -5.517896 0)
			(unlocked yes)
			(layer "F.Fab")
			(hide yes)
			(effects
				(font
					(size 1.016 1.016)
					(thickness 0.1524)
				)
			)
		)
		(duplicate_pad_numbers_are_jumpers no)
		(fp_line
			(start -0.508 -0.9398)
			(end -0.508 0.9398)
			(stroke
				(width 0.1524)
				(type default)
			)
			(layer "F.SilkS")
		)
		(fp_line
			(start 0.508 -0.9398)
			(end -0.508 -0.9398)
			(stroke
				(width 0.1524)
				(type default)
			)
			(layer "F.SilkS")
		)
		(fp_rect
			(start -0.508 0.9398)
			(end 0.508 -0.9398)
			(stroke
				(width 0)
				(type default)
			)
			(fill no)
			(layer "F.CrtYd")
		)
		(fp_rect
			(start -0.508 0.9398)
			(end 0.508 -0.9398)
			(stroke
				(width 0)
				(type default)
			)
			(fill no)
			(layer "F.Fab")
		)
		(pad "1" smd custom
			(at 0 -0.4445)
			(size 0.1397 0.1397)
			(layers "F.Cu" "F.Mask" "F.Paste")
			(net "PE_CLK_100M_DR2_1_R_P")
			(options
				(clearance outline)
				(anchor circle)
			)
			(primitives
				(gr_poly
					(pts
						(arc
							(start -0.1778 -0.2794)
							(mid -0.249642 -0.249642)
							(end -0.2794 -0.1778)
						)
						(arc
							(start -0.2794 0.1778)
							(mid -0.249642 0.249642)
							(end -0.1778 0.2794)
						)
						(arc
							(start 0.1778 0.2794)
							(mid 0.249642 0.249642)
							(end 0.2794 0.1778)
						)
						(arc
							(start 0.2794 -0.1778)
							(mid 0.249642 -0.249642)
							(end 0.1778 -0.2794)
						)
					)
					(width 0)
					(fill yes)
				)
			)
		)
		(pad "2" smd custom
			(at 0 0.4445)
			(size 0.1397 0.1397)
			(layers "F.Cu" "F.Mask" "F.Paste")
			(net "PE_CLK100M_DR2_1_P")
			(options
				(clearance outline)
				(anchor circle)
			)
			(primitives
				(gr_poly
					(pts
						(arc
							(start -0.1778 -0.2794)
							(mid -0.249642 -0.249642)
							(end -0.2794 -0.1778)
						)
						(arc
							(start -0.2794 0.1778)
							(mid -0.249642 0.249642)
							(end -0.1778 0.2794)
						)
						(arc
							(start 0.1778 0.2794)
							(mid 0.249642 0.249642)
							(end 0.2794 0.1778)
						)
						(arc
							(start 0.2794 -0.1778)
							(mid 0.249642 -0.249642)
							(end 0.1778 -0.2794)
						)
					)
					(width 0)
					(fill yes)
				)
			)
		)
	)
	(footprint ""
		(layer "F.Cu")
		(at 35.56 -142.24 180)
		(property "Reference" "Q69"
			(at 0 0 180)
			(layer "F.SilkS")
			(hide yes)
			(effects
				(font
					(size 1.27 1.27)
				)
			)
		)
		(property "Value" "2N7002A-7-GP"
			(at 0.127 -8.9662 180)
			(unlocked yes)
			(layer "F.Fab")
			(hide yes)
			(effects
				(font
					(size 1.016 1.016)
					(thickness 0.1524)
				)
			)
		)
		(property "Device Type" "SOT23DGS2D4H48"
			(at 0.127 -10.4902 180)
			(unlocked yes)
			(layer "F.Fab")
			(hide yes)
			(effects
				(font
					(size 1.016 1.016)
					(thickness 0.1524)
				)
			)
		)
		(duplicate_pad_numbers_are_jumpers no)
		(fp_line
			(start 1.651 1.778)
			(end 1.651 -1.778)
			(stroke
				(width 0.1524)
				(type default)
			)
			(layer "F.SilkS")
		)
		(fp_line
			(start 1.651 -1.778)
			(end -1.651 -1.778)
			(stroke
				(width 0.1524)
				(type default)
			)
			(layer "F.SilkS")
		)
		(fp_line
			(start -1.651 1.778)
			(end 1.651 1.778)
			(stroke
				(width 0.1524)
				(type default)
			)
			(layer "F.SilkS")
		)
		(fp_line
			(start -1.651 -1.778)
			(end -1.651 1.778)
			(stroke
				(width 0.1524)
				(type default)
			)
			(layer "F.SilkS")
		)
		(fp_poly
			(pts
				(xy -1.778 1.8796) (xy -1.778 -1.8796) (xy 1.778 -1.8796) (xy 1.778 1.8796)
			)
			(stroke
				(width 0)
				(type default)
			)
			(fill no)
			(layer "F.CrtYd")
		)
		(fp_poly
			(pts
				(xy -1.778 1.8796) (xy -1.778 -1.8796) (xy 1.778 -1.8796) (xy 1.778 1.8796)
			)
			(stroke
				(width 0)
				(type default)
			)
			(fill no)
			(layer "F.Fab")
		)
		(pad "D" smd custom
			(at 0 -0.9525 180)
			(size 0.1905 0.1905)
			(layers "F.Cu" "F.Mask" "F.Paste")
			(net "SSD8_CLK0_OE_MOS_N")
			(options
				(clearance outline)
				(anchor circle)
			)
			(primitives
				(gr_poly
					(pts
						(arc
							(start -0.1778 0.5715)
							(mid -0.321484 0.511984)
							(end -0.381 0.3683)
						)
						(arc
							(start -0.381 -0.3683)
							(mid -0.321484 -0.511984)
							(end -0.1778 -0.5715)
						)
						(arc
							(start 0.1778 -0.5715)
							(mid 0.321484 -0.511984)
							(end 0.381 -0.3683)
						)
						(arc
							(start 0.381 0.3683)
							(mid 0.321484 0.511984)
							(end 0.1778 0.5715)
						)
					)
					(width 0)
					(fill yes)
				)
			)
		)
		(pad "G" smd custom
			(at -0.98425 0.9525 180)
			(size 0.1905 0.1905)
			(layers "F.Cu" "F.Mask" "F.Paste")
			(net "SSD8_CLK0_OE_R_N")
			(options
				(clearance outline)
				(anchor circle)
			)
			(primitives
				(gr_poly
					(pts
						(arc
							(start -0.1778 0.5715)
							(mid -0.321484 0.511984)
							(end -0.381 0.3683)
						)
						(arc
							(start -0.381 -0.3683)
							(mid -0.321484 -0.511984)
							(end -0.1778 -0.5715)
						)
						(arc
							(start 0.1778 -0.5715)
							(mid 0.321484 -0.511984)
							(end 0.381 -0.3683)
						)
						(arc
							(start 0.381 0.3683)
							(mid 0.321484 0.511984)
							(end 0.1778 0.5715)
						)
					)
					(width 0)
					(fill yes)
				)
			)
		)
		(pad "S" smd custom
			(at 0.98425 0.9525 180)
			(size 0.1905 0.1905)
			(layers "F.Cu" "F.Mask" "F.Paste")
			(net "GND")
			(options
				(clearance outline)
				(anchor circle)
			)
			(primitives
				(gr_poly
					(pts
						(arc
							(start -0.1778 0.5715)
							(mid -0.321484 0.511984)
							(end -0.381 0.3683)
						)
						(arc
							(start -0.381 -0.3683)
							(mid -0.321484 -0.511984)
							(end -0.1778 -0.5715)
						)
						(arc
							(start 0.1778 -0.5715)
							(mid 0.321484 -0.511984)
							(end 0.381 -0.3683)
						)
						(arc
							(start 0.381 0.3683)
							(mid 0.321484 0.511984)
							(end 0.1778 0.5715)
						)
					)
					(width 0)
					(fill yes)
				)
			)
		)
	)
	(footprint ""
		(layer "F.Cu")
		(at 206.502 -398.526)
		(property "Reference" "D19"
			(at 0 0 0)
			(layer "F.SilkS")
			(hide yes)
			(effects
				(font
					(size 1.27 1.27)
				)
			)
		)
		(property "Value" "RB551V30-1-GP"
			(at 0 -6.7818 0)
			(unlocked yes)
			(layer "F.Fab")
			(hide yes)
			(effects
				(font
					(size 1.016 1.016)
					(thickness 0.1524)
				)
			)
		)
		(property "Device Type" "SOD323AKH44"
			(at 0 -8.6868 0)
			(unlocked yes)
			(layer "F.Fab")
			(hide yes)
			(effects
				(font
					(size 1.016 1.016)
					(thickness 0.1524)
				)
			)
		)
		(duplicate_pad_numbers_are_jumpers no)
		(fp_line
			(start -0.889 -1.9304)
			(end 0.889 -1.9304)
			(stroke
				(width 0.1524)
				(type default)
			)
			(layer "F.SilkS")
		)
		(fp_line
			(start -0.889 2.159)
			(end -0.889 -1.9304)
			(stroke
				(width 0.1524)
				(type default)
			)
			(layer "F.SilkS")
		)
		(fp_line
			(start 0.762 2.0574)
			(end -0.762 2.0574)
			(stroke
				(width 0.508)
				(type default)
			)
			(layer "F.SilkS")
		)
		(fp_line
			(start 0.889 -1.9304)
			(end 0.889 2.159)
			(stroke
				(width 0.1524)
				(type default)
			)
			(layer "F.SilkS")
		)
		(fp_line
			(start 0.889 2.159)
			(end -0.889 2.159)
			(stroke
				(width 0.1524)
				(type default)
			)
			(layer "F.SilkS")
		)
		(fp_rect
			(start -1.016 2.3114)
			(end 1.016 -2.0066)
			(stroke
				(width 0)
				(type default)
			)
			(fill no)
			(layer "F.CrtYd")
		)
		(fp_poly
			(pts
				(xy -1.016 -2.0066) (xy 1.016 -2.0066) (xy 1.016 2.3114) (xy -1.016 2.3114)
			)
			(stroke
				(width 0)
				(type default)
			)
			(fill no)
			(layer "F.Fab")
		)
		(pad "A" smd rect
			(at 0 -1.143)
			(size 0.5588 1.016)
			(layers "F.Cu" "F.Mask" "F.Paste")
			(net "SW_SSD1_R")
		)
		(pad "K" smd rect
			(at 0 1.143)
			(size 0.5588 1.016)
			(layers "F.Cu" "F.Mask" "F.Paste")
			(net "SW_SSD1_N")
		)
	)
	(footprint ""
		(layer "F.Cu")
		(at 96.52 -92.964)
		(property "Reference" "R9125"
			(at 0 0 0)
			(layer "F.SilkS")
			(hide yes)
			(effects
				(font
					(size 1.27 1.27)
				)
			)
		)
		(property "Value" "27R2F-GP"
			(at 0.064008 -3.993896 0)
			(unlocked yes)
			(layer "F.Fab")
			(hide yes)
			(effects
				(font
					(size 1.016 1.016)
					(thickness 0.1524)
				)
			)
		)
		(property "Device Type" "R402H16"
			(at 0.064008 -5.517896 0)
			(unlocked yes)
			(layer "F.Fab")
			(hide yes)
			(effects
				(font
					(size 1.016 1.016)
					(thickness 0.1524)
				)
			)
		)
		(duplicate_pad_numbers_are_jumpers no)
		(fp_line
			(start -0.508 -0.9398)
			(end -0.508 0.9398)
			(stroke
				(width 0.1524)
				(type default)
			)
			(layer "F.SilkS")
		)
		(fp_line
			(start 0.508 -0.9398)
			(end -0.508 -0.9398)
			(stroke
				(width 0.1524)
				(type default)
			)
			(layer "F.SilkS")
		)
		(fp_rect
			(start -0.508 0.9398)
			(end 0.508 -0.9398)
			(stroke
				(width 0)
				(type default)
			)
			(fill no)
			(layer "F.CrtYd")
		)
		(fp_rect
			(start -0.508 0.9398)
			(end 0.508 -0.9398)
			(stroke
				(width 0)
				(type default)
			)
			(fill no)
			(layer "F.Fab")
		)
		(pad "1" smd custom
			(at 0 -0.4445)
			(size 0.1397 0.1397)
			(layers "F.Cu" "F.Mask" "F.Paste")
			(net "PE_CLK_100M_DR14_2_R_N")
			(options
				(clearance outline)
				(anchor circle)
			)
			(primitives
				(gr_poly
					(pts
						(arc
							(start -0.1778 -0.2794)
							(mid -0.249642 -0.249642)
							(end -0.2794 -0.1778)
						)
						(arc
							(start -0.2794 0.1778)
							(mid -0.249642 0.249642)
							(end -0.1778 0.2794)
						)
						(arc
							(start 0.1778 0.2794)
							(mid 0.249642 0.249642)
							(end 0.2794 0.1778)
						)
						(arc
							(start 0.2794 -0.1778)
							(mid 0.249642 -0.249642)
							(end 0.1778 -0.2794)
						)
					)
					(width 0)
					(fill yes)
				)
			)
		)
		(pad "2" smd custom
			(at 0 0.4445)
			(size 0.1397 0.1397)
			(layers "F.Cu" "F.Mask" "F.Paste")
			(net "PE_CLK100M_DR14_2_N")
			(options
				(clearance outline)
				(anchor circle)
			)
			(primitives
				(gr_poly
					(pts
						(arc
							(start -0.1778 -0.2794)
							(mid -0.249642 -0.249642)
							(end -0.2794 -0.1778)
						)
						(arc
							(start -0.2794 0.1778)
							(mid -0.249642 0.249642)
							(end -0.1778 0.2794)
						)
						(arc
							(start 0.1778 0.2794)
							(mid 0.249642 0.249642)
							(end 0.2794 0.1778)
						)
						(arc
							(start 0.2794 -0.1778)
							(mid 0.249642 -0.249642)
							(end 0.1778 -0.2794)
						)
					)
					(width 0)
					(fill yes)
				)
			)
		)
	)
	(footprint ""
		(layer "F.Cu")
		(at 244.0178 -360.6038)
		(property "Reference" "C349"
			(at 0 0 0)
			(layer "F.SilkS")
			(hide yes)
			(effects
				(font
					(size 1.27 1.27)
				)
			)
		)
		(property "Value" "SC22U25V6KX-GP-U"
			(at -2.860802 -5.279644 0)
			(unlocked yes)
			(layer "F.Fab")
			(hide yes)
			(effects
				(font
					(size 1.016 1.016)
					(thickness 0.1524)
				)
			)
		)
		(property "Device Type" "C1206-TO0D3H75"
			(at -2.860802 -6.803644 0)
			(unlocked yes)
			(layer "F.Fab")
			(hide yes)
			(effects
				(font
					(size 1.016 1.016)
					(thickness 0.1524)
				)
			)
		)
		(duplicate_pad_numbers_are_jumpers no)
		(fp_line
			(start -1.3081 -2.3749)
			(end 1.3081 -2.3749)
			(stroke
				(width 0.1524)
				(type default)
			)
			(layer "F.SilkS")
		)
		(fp_line
			(start -1.3081 2.3749)
			(end -1.3081 -2.3749)
			(stroke
				(width 0.1524)
				(type default)
			)
			(layer "F.SilkS")
		)
		(fp_line
			(start 1.3081 -2.3749)
			(end 1.3081 2.3749)
			(stroke
				(width 0.1524)
				(type default)
			)
			(layer "F.SilkS")
		)
		(fp_line
			(start 1.3081 2.3749)
			(end -1.3081 2.3749)
			(stroke
				(width 0.1524)
				(type default)
			)
			(layer "F.SilkS")
		)
		(fp_rect
			(start -0.8001 1.6002)
			(end 0.8001 -1.6002)
			(stroke
				(width 0)
				(type default)
			)
			(fill no)
			(layer "F.CrtYd")
		)
		(fp_poly
			(pts
				(xy -1.5621 2.4511) (xy -1.5621 1.6002) (xy 0.8001 1.6002) (xy 0.8001 -1.6002) (xy -0.8001 -1.6002)
				(xy -0.8001 1.5875) (xy -1.5621 1.5875) (xy -1.5621 -2.4511) (xy 1.5621 -2.4511) (xy 1.5621 2.4511)
			)
			(stroke
				(width 0)
				(type default)
			)
			(fill no)
			(layer "F.CrtYd")
		)
		(fp_rect
			(start -1.5621 2.4511)
			(end 1.5621 -2.4511)
			(stroke
				(width 0)
				(type default)
			)
			(fill no)
			(layer "F.Fab")
		)
		(pad "1" smd rect
			(at 0 -1.392936)
			(size 2.1082 1.4478)
			(layers "F.Cu" "F.Mask" "F.Paste")
			(net "P12V")
		)
		(pad "2" smd rect
			(at 0 1.392936)
			(size 2.1082 1.4478)
			(layers "F.Cu" "F.Mask" "F.Paste")
			(net "GND")
		)
	)
	(footprint ""
		(layer "F.Cu")
		(at 99.949 -105.791)
		(property "Reference" "C8874"
			(at 0 0 0)
			(layer "F.SilkS")
			(hide yes)
			(effects
				(font
					(size 1.27 1.27)
				)
			)
		)
		(property "Value" "SCD1U16V2KX-3GP"
			(at 1.1811 -2.7051 0)
			(unlocked yes)
			(layer "F.Fab")
			(hide yes)
			(effects
				(font
					(size 1.016 1.016)
					(thickness 0.1524)
				)
			)
		)
		(property "Device Type" "C402H22"
			(at 1.1811 -4.2291 0)
			(unlocked yes)
			(layer "F.Fab")
			(hide yes)
			(effects
				(font
					(size 1.016 1.016)
					(thickness 0.1524)
				)
			)
		)
		(duplicate_pad_numbers_are_jumpers no)
		(fp_rect
			(start -0.4318 0.9525)
			(end 0.4318 -0.9525)
			(stroke
				(width 0)
				(type default)
			)
			(fill no)
			(layer "F.CrtYd")
		)
		(fp_rect
			(start -0.4318 0.9525)
			(end 0.4318 -0.9525)
			(stroke
				(width 0)
				(type default)
			)
			(fill no)
			(layer "F.Fab")
		)
		(pad "1" smd custom
			(at 0 -0.4445)
			(size 0.1524 0.1524)
			(layers "F.Cu" "F.Mask" "F.Paste")
			(net "VDD_IO_4")
			(options
				(clearance outline)
				(anchor circle)
			)
			(primitives
				(gr_poly
					(pts
						(arc
							(start 0.3048 -0.2032)
							(mid 0.275042 -0.275042)
							(end 0.2032 -0.3048)
						)
						(arc
							(start -0.2032 -0.3048)
							(mid -0.275042 -0.275042)
							(end -0.3048 -0.2032)
						)
						(arc
							(start -0.3048 0.2032)
							(mid -0.275042 0.275042)
							(end -0.2032 0.3048)
						)
						(arc
							(start 0.2032 0.3048)
							(mid 0.275042 0.275042)
							(end 0.3048 0.2032)
						)
					)
					(width 0)
					(fill yes)
				)
			)
		)
		(pad "2" smd custom
			(at 0 0.4445)
			(size 0.1524 0.1524)
			(layers "F.Cu" "F.Mask" "F.Paste")
			(net "GND")
			(options
				(clearance outline)
				(anchor circle)
			)
			(primitives
				(gr_poly
					(pts
						(arc
							(start 0.3048 -0.2032)
							(mid 0.275042 -0.275042)
							(end 0.2032 -0.3048)
						)
						(arc
							(start -0.2032 -0.3048)
							(mid -0.275042 -0.275042)
							(end -0.3048 -0.2032)
						)
						(arc
							(start -0.3048 0.2032)
							(mid -0.275042 0.275042)
							(end -0.2032 0.3048)
						)
						(arc
							(start 0.2032 0.3048)
							(mid 0.275042 0.275042)
							(end 0.3048 0.2032)
						)
					)
					(width 0)
					(fill yes)
				)
			)
		)
	)
)
